# T6G (Grand Teton) — schematic netlist excerpt (pin names and nets, part order shuffled) for the footprints in the layout excerpt that follows; sources: Cadence DE-HDL packaged netlist, KiCad conversion of 04192023_DAF0TMB3IC0_F0TG_MB_C_brd_V02_OCP.brd

R3587  Q_RES  33.2 1% CHIP  pkg 0402LF  page 251 : A = SMB_INA230_3V3AUX_SDA ; B = SMB_INA230_1_3V3AUX_SDA_R
PR157  Q_RES  40.2K 1% CHIP  pkg 0402LF  page 210 : A = P5V_AUX ; B = PVDDCR_CPU0_P1_VMON

(kicad_pcb
	(version 20260206)
	(generator "pcbnew")
	(generator_version "10.0")
	(general
		(thickness 1.6)
		(legacy_teardrops no)
	)
	(paper "A4")
	(title_block
		(title "04192023_DAF0TMB3IC0_F0TG_MB_C_brd_V02_OCP.brd")
		(comment 1 "Grand Teton / footprints 1011-1012 of 8354")
	)
	(layers
		(0 "F.Cu" signal "TOP")
		(4 "In1.Cu" signal "GND")
		(6 "In2.Cu" signal "IN1")
		(8 "In3.Cu" signal "GND1")
		(10 "In4.Cu" signal "IN2")
		(12 "In5.Cu" signal "GND2")
		(14 "In6.Cu" signal "IN3")
		(16 "In7.Cu" signal "GND3")
		(18 "In8.Cu" signal "VCC")
		(20 "In9.Cu" signal "VCC1")
		(22 "In10.Cu" signal "GND4")
		(24 "In11.Cu" signal "IN4")
		(26 "In12.Cu" signal "GND5")
		(28 "In13.Cu" signal "IN5")
		(30 "In14.Cu" signal "GND6")
		(32 "In15.Cu" signal "IN6")
		(34 "In16.Cu" signal "GND7")
		(2 "B.Cu" signal "BOTTOM")
		(9 "F.Adhes" user "F.Adhesive")
		(11 "B.Adhes" user "B.Adhesive")
		(13 "F.Paste" user "Package Geometry/Pastemask Top")
		(15 "B.Paste" user "Package Geometry/Pastemask Bottom")
		(5 "F.SilkS" user "Ref Des/Silkscreen Top")
		(7 "B.SilkS" user "Ref Des/Silkscreen Bottom")
		(1 "F.Mask" user "Board Geometry/Soldermask Top")
		(3 "B.Mask" user "Board Geometry/Soldermask Bottom")
		(17 "Dwgs.User" user "User.Drawings")
		(19 "Cmts.User" user "User.Comments")
		(21 "Eco1.User" user "User.Eco1")
		(23 "Eco2.User" user "User.Eco2")
		(25 "Edge.Cuts" user "Board Geometry/Outline")
		(27 "Margin" user)
		(31 "F.CrtYd" user "Package Geometry/Place Bound Top")
		(29 "B.CrtYd" user "Package Geometry/Place Bound Bottom")
		(35 "F.Fab" user "Ref Des/Assembly Top")
		(33 "B.Fab" user "Ref Des/Assembly Bottom")
	)
	(footprint ""
		(layer "F.Cu")
		(at 299.935646 -117.65026 90)
		(property "Reference" "R3587"
			(at 0 0 90)
			(layer "F.SilkS")
			(hide yes)
			(effects
				(font
					(size 1.27 1.27)
				)
			)
		)
		(property "Value" ""
			(at 0 0 90)
			(layer "F.Fab")
			(effects
				(font
					(size 1.27 1.27)
				)
			)
		)
		(duplicate_pad_numbers_are_jumpers no)
		(fp_line
			(start 0.7874 -0.4064)
			(end 0.7874 0.4064)
			(stroke
				(width 0.1524)
				(type default)
			)
			(layer "F.SilkS")
		)
		(fp_line
			(start -0.7874 -0.4064)
			(end 0.7874 -0.4064)
			(stroke
				(width 0.1524)
				(type default)
			)
			(layer "F.SilkS")
		)
		(fp_line
			(start 0.7874 0.4064)
			(end -0.7874 0.4064)
			(stroke
				(width 0.1524)
				(type default)
			)
			(layer "F.SilkS")
		)
		(fp_line
			(start -0.7874 0.4064)
			(end -0.7874 -0.4064)
			(stroke
				(width 0.1524)
				(type default)
			)
			(layer "F.SilkS")
		)
		(fp_line
			(start -0.12065 -0.305054)
			(end -0.12065 -0.2794)
			(stroke
				(width 0.1)
				(type default)
			)
			(layer "F.Fab")
		)
		(fp_line
			(start -0.67945 -0.305054)
			(end -0.12065 -0.305054)
			(stroke
				(width 0.1)
				(type default)
			)
			(layer "F.Fab")
		)
		(fp_line
			(start 0.67945 -0.3048)
			(end 0.67945 0.3048)
			(stroke
				(width 0.1)
				(type default)
			)
			(layer "F.Fab")
		)
		(fp_line
			(start 0.12065 -0.3048)
			(end 0.67945 -0.3048)
			(stroke
				(width 0.1)
				(type default)
			)
			(layer "F.Fab")
		)
		(fp_line
			(start 0.12065 -0.2794)
			(end 0.12065 -0.3048)
			(stroke
				(width 0.1)
				(type default)
			)
			(layer "F.Fab")
		)
		(fp_line
			(start -0.12065 -0.2794)
			(end 0.12065 -0.2794)
			(stroke
				(width 0.1)
				(type default)
			)
			(layer "F.Fab")
		)
		(fp_line
			(start 0.120396 0.2794)
			(end -0.12065 0.2794)
			(stroke
				(width 0.1)
				(type default)
			)
			(layer "F.Fab")
		)
		(fp_line
			(start -0.12065 0.2794)
			(end -0.12065 0.3048)
			(stroke
				(width 0.1)
				(type default)
			)
			(layer "F.Fab")
		)
		(fp_line
			(start 0.67945 0.3048)
			(end 0.120396 0.3048)
			(stroke
				(width 0.1)
				(type default)
			)
			(layer "F.Fab")
		)
		(fp_line
			(start 0.120396 0.3048)
			(end 0.120396 0.2794)
			(stroke
				(width 0.1)
				(type default)
			)
			(layer "F.Fab")
		)
		(fp_line
			(start -0.12065 0.3048)
			(end -0.67945 0.3048)
			(stroke
				(width 0.1)
				(type default)
			)
			(layer "F.Fab")
		)
		(fp_line
			(start -0.67945 0.3048)
			(end -0.67945 -0.305054)
			(stroke
				(width 0.1)
				(type default)
			)
			(layer "F.Fab")
		)
		(pad "1" smd circle
			(at -0.40005 0 90)
			(size 0 0)
			(layers "F.Cu" "F.Mask" "F.Paste")
			(net "SMB_INA230_3V3AUX_SDA")
		)
		(pad "2" smd circle
			(at 0.40005 0 90)
			(size 0 0)
			(layers "F.Cu" "F.Mask" "F.Paste")
			(net "SMB_INA230_1_3V3AUX_SDA_R")
		)
	)
	(footprint ""
		(layer "F.Cu")
		(at 101.948234 -142.59941 180)
		(property "Reference" "PR157"
			(at 0 0 180)
			(layer "F.SilkS")
			(hide yes)
			(effects
				(font
					(size 1.27 1.27)
				)
			)
		)
		(property "Value" ""
			(at 0 0 180)
			(layer "F.Fab")
			(effects
				(font
					(size 1.27 1.27)
				)
			)
		)
		(duplicate_pad_numbers_are_jumpers no)
		(fp_line
			(start 0.7874 0.4064)
			(end -0.7874 0.4064)
			(stroke
				(width 0.1524)
				(type default)
			)
			(layer "F.SilkS")
		)
		(fp_line
			(start 0.7874 -0.4064)
			(end 0.7874 0.4064)
			(stroke
				(width 0.1524)
				(type default)
			)
			(layer "F.SilkS")
		)
		(fp_line
			(start -0.7874 0.4064)
			(end -0.7874 -0.4064)
			(stroke
				(width 0.1524)
				(type default)
			)
			(layer "F.SilkS")
		)
		(fp_line
			(start -0.7874 -0.4064)
			(end 0.7874 -0.4064)
			(stroke
				(width 0.1524)
				(type default)
			)
			(layer "F.SilkS")
		)
		(fp_line
			(start 0.67945 0.3048)
			(end 0.120396 0.3048)
			(stroke
				(width 0.1)
				(type default)
			)
			(layer "F.Fab")
		)
		(fp_line
			(start 0.67945 -0.3048)
			(end 0.67945 0.3048)
			(stroke
				(width 0.1)
				(type default)
			)
			(layer "F.Fab")
		)
		(fp_line
			(start 0.12065 -0.2794)
			(end 0.12065 -0.3048)
			(stroke
				(width 0.1)
				(type default)
			)
			(layer "F.Fab")
		)
		(fp_line
			(start 0.12065 -0.3048)
			(end 0.67945 -0.3048)
			(stroke
				(width 0.1)
				(type default)
			)
			(layer "F.Fab")
		)
		(fp_line
			(start 0.120396 0.3048)
			(end 0.120396 0.2794)
			(stroke
				(width 0.1)
				(type default)
			)
			(layer "F.Fab")
		)
		(fp_line
			(start 0.120396 0.2794)
			(end -0.12065 0.2794)
			(stroke
				(width 0.1)
				(type default)
			)
			(layer "F.Fab")
		)
		(fp_line
			(start -0.12065 0.3048)
			(end -0.67945 0.3048)
			(stroke
				(width 0.1)
				(type default)
			)
			(layer "F.Fab")
		)
		(fp_line
			(start -0.12065 0.2794)
			(end -0.12065 0.3048)
			(stroke
				(width 0.1)
				(type default)
			)
			(layer "F.Fab")
		)
		(fp_line
			(start -0.12065 -0.2794)
			(end 0.12065 -0.2794)
			(stroke
				(width 0.1)
				(type default)
			)
			(layer "F.Fab")
		)
		(fp_line
			(start -0.12065 -0.305054)
			(end -0.12065 -0.2794)
			(stroke
				(width 0.1)
				(type default)
			)
			(layer "F.Fab")
		)
		(fp_line
			(start -0.67945 0.3048)
			(end -0.67945 -0.305054)
			(stroke
				(width 0.1)
				(type default)
			)
			(layer "F.Fab")
		)
		(fp_line
			(start -0.67945 -0.305054)
			(end -0.12065 -0.305054)
			(stroke
				(width 0.1)
				(type default)
			)
			(layer "F.Fab")
		)
		(pad "1" smd circle
			(at -0.40005 0 180)
			(size 0 0)
			(layers "F.Cu" "F.Mask" "F.Paste")
			(net "P5V_AUX")
		)
		(pad "2" smd circle
			(at 0.40005 0 180)
			(size 0 0)
			(layers "F.Cu" "F.Mask" "F.Paste")
			(net "PVDDCR_CPU0_P1_VMON")
		)
	)
)
